(kicad_pcb
	(version 20260206)
	(generator "pcbnew")
	(generator_version "10.0")
	(general
		(thickness 1.6)
		(legacy_teardrops no)
	)
	(paper "A4")
	(title_block
		(title "01162023_DA0F0TEBIF0_F0T_Expander_BD_F_brd_V02_OCP.brd")
		(comment 1 "Grand Teton / footprints 2735-2742 of 9728")
	)
	(layers
		(0 "F.Cu" signal "TOP")
		(4 "In1.Cu" signal "GND")
		(6 "In2.Cu" signal "VCC")
		(8 "In3.Cu" signal "VCC1")
		(10 "In4.Cu" signal "GND1")
		(12 "In5.Cu" signal "IN1")
		(14 "In6.Cu" signal "GND2")
		(16 "In7.Cu" signal "IN2")
		(18 "In8.Cu" signal "GND3")
		(20 "In9.Cu" signal "IN3")
		(22 "In10.Cu" signal "GND4")
		(24 "In11.Cu" signal "IN4")
		(26 "In12.Cu" signal "GND5")
		(28 "In13.Cu" signal "IN5")
		(30 "In14.Cu" signal "GND6")
		(32 "In15.Cu" signal "IN6")
		(34 "In16.Cu" signal "GND7")
		(2 "B.Cu" signal "BOTTOM")
		(9 "F.Adhes" user "F.Adhesive")
		(11 "B.Adhes" user "B.Adhesive")
		(13 "F.Paste" user "Package Geometry/Pastemask Top")
		(15 "B.Paste" user "Package Geometry/Pastemask Bottom")
		(5 "F.SilkS" user "Ref Des/Silkscreen Top")
		(7 "B.SilkS" user "Ref Des/Silkscreen Bottom")
		(1 "F.Mask" user "Board Geometry/Soldermask Top")
		(3 "B.Mask" user "Board Geometry/Soldermask Bottom")
		(17 "Dwgs.User" user "User.Drawings")
		(19 "Cmts.User" user "User.Comments")
		(21 "Eco1.User" user "User.Eco1")
		(23 "Eco2.User" user "User.Eco2")
		(25 "Edge.Cuts" user "Board Geometry/Outline")
		(27 "Margin" user)
		(31 "F.CrtYd" user "Package Geometry/Place Bound Top")
		(29 "B.CrtYd" user "Package Geometry/Place Bound Bottom")
		(35 "F.Fab" user "Ref Des/Assembly Top")
		(33 "B.Fab" user "Ref Des/Assembly Bottom")
	)
	(footprint ""
		(layer "F.Cu")
		(at 404.953978 -381.90297 -90)
		(property "Reference" "C3997"
			(at 0 0 270)
			(layer "F.SilkS")
			(hide yes)
			(effects
				(font
					(size 1.27 1.27)
				)
			)
		)
		(property "Value" ""
			(at 0 0 270)
			(layer "F.Fab")
			(effects
				(font
					(size 1.27 1.27)
				)
			)
		)
		(duplicate_pad_numbers_are_jumpers no)
		(fp_line
			(start -0.7874 0.4064)
			(end -0.7874 -0.4064)
			(stroke
				(width 0.1524)
				(type default)
			)
			(layer "F.SilkS")
		)
		(fp_line
			(start 0.7874 0.4064)
			(end -0.7874 0.4064)
			(stroke
				(width 0.1524)
				(type default)
			)
			(layer "F.SilkS")
		)
		(fp_line
			(start -0.7874 -0.4064)
			(end 0.7874 -0.4064)
			(stroke
				(width 0.1524)
				(type default)
			)
			(layer "F.SilkS")
		)
		(fp_line
			(start 0.7874 -0.4064)
			(end 0.7874 0.4064)
			(stroke
				(width 0.1524)
				(type default)
			)
			(layer "F.SilkS")
		)
		(fp_line
			(start -0.67945 0.3048)
			(end -0.67945 -0.305054)
			(stroke
				(width 0.1)
				(type default)
			)
			(layer "F.Fab")
		)
		(fp_line
			(start -0.12065 0.3048)
			(end -0.67945 0.3048)
			(stroke
				(width 0.1)
				(type default)
			)
			(layer "F.Fab")
		)
		(fp_line
			(start 0.120396 0.3048)
			(end 0.120396 0.2794)
			(stroke
				(width 0.1)
				(type default)
			)
			(layer "F.Fab")
		)
		(fp_line
			(start 0.67945 0.3048)
			(end 0.120396 0.3048)
			(stroke
				(width 0.1)
				(type default)
			)
			(layer "F.Fab")
		)
		(fp_line
			(start -0.12065 0.2794)
			(end -0.12065 0.3048)
			(stroke
				(width 0.1)
				(type default)
			)
			(layer "F.Fab")
		)
		(fp_line
			(start 0.120396 0.2794)
			(end -0.12065 0.2794)
			(stroke
				(width 0.1)
				(type default)
			)
			(layer "F.Fab")
		)
		(fp_line
			(start -0.12065 -0.2794)
			(end 0.12065 -0.2794)
			(stroke
				(width 0.1)
				(type default)
			)
			(layer "F.Fab")
		)
		(fp_line
			(start 0.12065 -0.2794)
			(end 0.12065 -0.3048)
			(stroke
				(width 0.1)
				(type default)
			)
			(layer "F.Fab")
		)
		(fp_line
			(start 0.12065 -0.3048)
			(end 0.67945 -0.3048)
			(stroke
				(width 0.1)
				(type default)
			)
			(layer "F.Fab")
		)
		(fp_line
			(start 0.67945 -0.3048)
			(end 0.67945 0.3048)
			(stroke
				(width 0.1)
				(type default)
			)
			(layer "F.Fab")
		)
		(fp_line
			(start -0.67945 -0.305054)
			(end -0.12065 -0.305054)
			(stroke
				(width 0.1)
				(type default)
			)
			(layer "F.Fab")
		)
		(fp_line
			(start -0.12065 -0.305054)
			(end -0.12065 -0.2794)
			(stroke
				(width 0.1)
				(type default)
			)
			(layer "F.Fab")
		)
		(pad "1" smd circle
			(at -0.40005 0 270)
			(size 0 0)
			(layers "F.Cu" "F.Mask" "F.Paste")
			(net "GND")
		)
		(pad "2" smd circle
			(at 0.40005 0 270)
			(size 0 0)
			(layers "F.Cu" "F.Mask" "F.Paste")
			(net "P3V3_AUX")
		)
	)
	(footprint ""
		(layer "F.Cu")
		(at 26.584148 -29.222954 -90)
		(property "Reference" "PC669"
			(at 0 0 270)
			(layer "F.SilkS")
			(hide yes)
			(effects
				(font
					(size 1.27 1.27)
				)
			)
		)
		(property "Value" ""
			(at 0 0 270)
			(layer "F.Fab")
			(effects
				(font
					(size 1.27 1.27)
				)
			)
		)
		(duplicate_pad_numbers_are_jumpers no)
		(fp_line
			(start -0.7874 0.4064)
			(end -0.7874 -0.4064)
			(stroke
				(width 0.1524)
				(type default)
			)
			(layer "F.SilkS")
		)
		(fp_line
			(start 0.7874 0.4064)
			(end -0.7874 0.4064)
			(stroke
				(width 0.1524)
				(type default)
			)
			(layer "F.SilkS")
		)
		(fp_line
			(start -0.7874 -0.4064)
			(end 0.7874 -0.4064)
			(stroke
				(width 0.1524)
				(type default)
			)
			(layer "F.SilkS")
		)
		(fp_line
			(start 0.7874 -0.4064)
			(end 0.7874 0.4064)
			(stroke
				(width 0.1524)
				(type default)
			)
			(layer "F.SilkS")
		)
		(fp_line
			(start -0.67945 0.3048)
			(end -0.67945 -0.305054)
			(stroke
				(width 0.1)
				(type default)
			)
			(layer "F.Fab")
		)
		(fp_line
			(start -0.12065 0.3048)
			(end -0.67945 0.3048)
			(stroke
				(width 0.1)
				(type default)
			)
			(layer "F.Fab")
		)
		(fp_line
			(start 0.120396 0.3048)
			(end 0.120396 0.2794)
			(stroke
				(width 0.1)
				(type default)
			)
			(layer "F.Fab")
		)
		(fp_line
			(start 0.67945 0.3048)
			(end 0.120396 0.3048)
			(stroke
				(width 0.1)
				(type default)
			)
			(layer "F.Fab")
		)
		(fp_line
			(start -0.12065 0.2794)
			(end -0.12065 0.3048)
			(stroke
				(width 0.1)
				(type default)
			)
			(layer "F.Fab")
		)
		(fp_line
			(start 0.120396 0.2794)
			(end -0.12065 0.2794)
			(stroke
				(width 0.1)
				(type default)
			)
			(layer "F.Fab")
		)
		(fp_line
			(start -0.12065 -0.2794)
			(end 0.12065 -0.2794)
			(stroke
				(width 0.1)
				(type default)
			)
			(layer "F.Fab")
		)
		(fp_line
			(start 0.12065 -0.2794)
			(end 0.12065 -0.3048)
			(stroke
				(width 0.1)
				(type default)
			)
			(layer "F.Fab")
		)
		(fp_line
			(start 0.12065 -0.3048)
			(end 0.67945 -0.3048)
			(stroke
				(width 0.1)
				(type default)
			)
			(layer "F.Fab")
		)
		(fp_line
			(start 0.67945 -0.3048)
			(end 0.67945 0.3048)
			(stroke
				(width 0.1)
				(type default)
			)
			(layer "F.Fab")
		)
		(fp_line
			(start -0.67945 -0.305054)
			(end -0.12065 -0.305054)
			(stroke
				(width 0.1)
				(type default)
			)
			(layer "F.Fab")
		)
		(fp_line
			(start -0.12065 -0.305054)
			(end -0.12065 -0.2794)
			(stroke
				(width 0.1)
				(type default)
			)
			(layer "F.Fab")
		)
		(pad "1" smd circle
			(at -0.40005 0 270)
			(size 0 0)
			(layers "F.Cu" "F.Mask" "F.Paste")
			(net "P3V3_AUX")
		)
		(pad "2" smd circle
			(at 0.40005 0 270)
			(size 0 0)
			(layers "F.Cu" "F.Mask" "F.Paste")
			(net "GND")
		)
	)
	(footprint ""
		(layer "F.Cu")
		(at 335.154524 -356.244906 90)
		(property "Reference" "C528"
			(at 0 0 90)
			(layer "F.SilkS")
			(hide yes)
			(effects
				(font
					(size 1.27 1.27)
				)
			)
		)
		(property "Value" ""
			(at 0 0 90)
			(layer "F.Fab")
			(effects
				(font
					(size 1.27 1.27)
				)
			)
		)
		(duplicate_pad_numbers_are_jumpers no)
		(fp_line
			(start 0.299974 -0.150114)
			(end 0.299974 0.150114)
			(stroke
				(width 0.1)
				(type default)
			)
			(layer "F.Fab")
		)
		(fp_line
			(start -0.299974 -0.150114)
			(end 0.299974 -0.150114)
			(stroke
				(width 0.1)
				(type default)
			)
			(layer "F.Fab")
		)
		(fp_line
			(start 0.299974 0.150114)
			(end -0.299974 0.150114)
			(stroke
				(width 0.1)
				(type default)
			)
			(layer "F.Fab")
		)
		(fp_line
			(start -0.299974 0.150114)
			(end -0.299974 -0.150114)
			(stroke
				(width 0.1)
				(type default)
			)
			(layer "F.Fab")
		)
		(pad "1" smd rect
			(at -0.2667 0 90)
			(size 0.3048 0.381)
			(layers "F.Cu" "F.Mask" "F.Paste")
			(net "P5E_PEX2_STN5_TX_DN<91>")
		)
		(pad "2" smd rect
			(at 0.2667 0 90)
			(size 0.3048 0.381)
			(layers "F.Cu" "F.Mask" "F.Paste")
			(net "P5E_PEX2_STN5_TX_C_DN<91>")
		)
	)
	(footprint ""
		(layer "F.Cu")
		(at 153.650442 -250.070874 -90)
		(property "Reference" "R1279"
			(at 0 0 270)
			(layer "F.SilkS")
			(hide yes)
			(effects
				(font
					(size 1.27 1.27)
				)
			)
		)
		(property "Value" ""
			(at 0 0 270)
			(layer "F.Fab")
			(effects
				(font
					(size 1.27 1.27)
				)
			)
		)
		(duplicate_pad_numbers_are_jumpers no)
		(fp_line
			(start -0.7874 0.4064)
			(end -0.7874 -0.4064)
			(stroke
				(width 0.1524)
				(type default)
			)
			(layer "F.SilkS")
		)
		(fp_line
			(start 0.7874 0.4064)
			(end -0.7874 0.4064)
			(stroke
				(width 0.1524)
				(type default)
			)
			(layer "F.SilkS")
		)
		(fp_line
			(start -0.7874 -0.4064)
			(end 0.7874 -0.4064)
			(stroke
				(width 0.1524)
				(type default)
			)
			(layer "F.SilkS")
		)
		(fp_line
			(start 0.7874 -0.4064)
			(end 0.7874 0.4064)
			(stroke
				(width 0.1524)
				(type default)
			)
			(layer "F.SilkS")
		)
		(fp_line
			(start -0.67945 0.3048)
			(end -0.67945 -0.305054)
			(stroke
				(width 0.1)
				(type default)
			)
			(layer "F.Fab")
		)
		(fp_line
			(start -0.12065 0.3048)
			(end -0.67945 0.3048)
			(stroke
				(width 0.1)
				(type default)
			)
			(layer "F.Fab")
		)
		(fp_line
			(start 0.120396 0.3048)
			(end 0.120396 0.2794)
			(stroke
				(width 0.1)
				(type default)
			)
			(layer "F.Fab")
		)
		(fp_line
			(start 0.67945 0.3048)
			(end 0.120396 0.3048)
			(stroke
				(width 0.1)
				(type default)
			)
			(layer "F.Fab")
		)
		(fp_line
			(start -0.12065 0.2794)
			(end -0.12065 0.3048)
			(stroke
				(width 0.1)
				(type default)
			)
			(layer "F.Fab")
		)
		(fp_line
			(start 0.120396 0.2794)
			(end -0.12065 0.2794)
			(stroke
				(width 0.1)
				(type default)
			)
			(layer "F.Fab")
		)
		(fp_line
			(start -0.12065 -0.2794)
			(end 0.12065 -0.2794)
			(stroke
				(width 0.1)
				(type default)
			)
			(layer "F.Fab")
		)
		(fp_line
			(start 0.12065 -0.2794)
			(end 0.12065 -0.3048)
			(stroke
				(width 0.1)
				(type default)
			)
			(layer "F.Fab")
		)
		(fp_line
			(start 0.12065 -0.3048)
			(end 0.67945 -0.3048)
			(stroke
				(width 0.1)
				(type default)
			)
			(layer "F.Fab")
		)
		(fp_line
			(start 0.67945 -0.3048)
			(end 0.67945 0.3048)
			(stroke
				(width 0.1)
				(type default)
			)
			(layer "F.Fab")
		)
		(fp_line
			(start -0.67945 -0.305054)
			(end -0.12065 -0.305054)
			(stroke
				(width 0.1)
				(type default)
			)
			(layer "F.Fab")
		)
		(fp_line
			(start -0.12065 -0.305054)
			(end -0.12065 -0.2794)
			(stroke
				(width 0.1)
				(type default)
			)
			(layer "F.Fab")
		)
		(pad "1" smd circle
			(at -0.40005 0 270)
			(size 0 0)
			(layers "F.Cu" "F.Mask" "F.Paste")
			(net "PEX1_MODE_SEL10")
		)
		(pad "2" smd circle
			(at 0.40005 0 270)
			(size 0 0)
			(layers "F.Cu" "F.Mask" "F.Paste")
			(net "P1V8_PEX")
		)
	)
	(footprint ""
		(layer "F.Cu")
		(at 196.119242 -147.104608 180)
		(property "Reference" "C222"
			(at 0 0 180)
			(layer "F.SilkS")
			(hide yes)
			(effects
				(font
					(size 1.27 1.27)
				)
			)
		)
		(property "Value" ""
			(at 0 0 180)
			(layer "F.Fab")
			(effects
				(font
					(size 1.27 1.27)
				)
			)
		)
		(duplicate_pad_numbers_are_jumpers no)
		(fp_line
			(start 0.299974 0.150114)
			(end -0.299974 0.150114)
			(stroke
				(width 0.1)
				(type default)
			)
			(layer "F.Fab")
		)
		(fp_line
			(start 0.299974 -0.150114)
			(end 0.299974 0.150114)
			(stroke
				(width 0.1)
				(type default)
			)
			(layer "F.Fab")
		)
		(fp_line
			(start -0.299974 0.150114)
			(end -0.299974 -0.150114)
			(stroke
				(width 0.1)
				(type default)
			)
			(layer "F.Fab")
		)
		(fp_line
			(start -0.299974 -0.150114)
			(end 0.299974 -0.150114)
			(stroke
				(width 0.1)
				(type default)
			)
			(layer "F.Fab")
		)
		(pad "1" smd rect
			(at -0.2667 0 180)
			(size 0.3048 0.381)
			(layers "F.Cu" "F.Mask" "F.Paste")
			(net "P5E_PEX1_STN0_TX_DP<10>")
		)
		(pad "2" smd rect
			(at 0.2667 0 180)
			(size 0.3048 0.381)
			(layers "F.Cu" "F.Mask" "F.Paste")
			(net "P5E_PEX1_STN0_TX_C_DP<10>")
		)
	)
	(footprint ""
		(layer "F.Cu")
		(at 408.41041 -63.652146 180)
		(property "Reference" "R6026"
			(at 0 0 180)
			(layer "F.SilkS")
			(hide yes)
			(effects
				(font
					(size 1.27 1.27)
				)
			)
		)
		(property "Value" ""
			(at 0 0 180)
			(layer "F.Fab")
			(effects
				(font
					(size 1.27 1.27)
				)
			)
		)
		(duplicate_pad_numbers_are_jumpers no)
		(fp_line
			(start 0.7874 0.4064)
			(end -0.7874 0.4064)
			(stroke
				(width 0.1524)
				(type default)
			)
			(layer "F.SilkS")
		)
		(fp_line
			(start 0.7874 -0.4064)
			(end 0.7874 0.4064)
			(stroke
				(width 0.1524)
				(type default)
			)
			(layer "F.SilkS")
		)
		(fp_line
			(start -0.7874 0.4064)
			(end -0.7874 -0.4064)
			(stroke
				(width 0.1524)
				(type default)
			)
			(layer "F.SilkS")
		)
		(fp_line
			(start -0.7874 -0.4064)
			(end 0.7874 -0.4064)
			(stroke
				(width 0.1524)
				(type default)
			)
			(layer "F.SilkS")
		)
		(fp_line
			(start 0.67945 0.3048)
			(end 0.120396 0.3048)
			(stroke
				(width 0.1)
				(type default)
			)
			(layer "F.Fab")
		)
		(fp_line
			(start 0.67945 -0.3048)
			(end 0.67945 0.3048)
			(stroke
				(width 0.1)
				(type default)
			)
			(layer "F.Fab")
		)
		(fp_line
			(start 0.12065 -0.2794)
			(end 0.12065 -0.3048)
			(stroke
				(width 0.1)
				(type default)
			)
			(layer "F.Fab")
		)
		(fp_line
			(start 0.12065 -0.3048)
			(end 0.67945 -0.3048)
			(stroke
				(width 0.1)
				(type default)
			)
			(layer "F.Fab")
		)
		(fp_line
			(start 0.120396 0.3048)
			(end 0.120396 0.2794)
			(stroke
				(width 0.1)
				(type default)
			)
			(layer "F.Fab")
		)
		(fp_line
			(start 0.120396 0.2794)
			(end -0.12065 0.2794)
			(stroke
				(width 0.1)
				(type default)
			)
			(layer "F.Fab")
		)
		(fp_line
			(start -0.12065 0.3048)
			(end -0.67945 0.3048)
			(stroke
				(width 0.1)
				(type default)
			)
			(layer "F.Fab")
		)
		(fp_line
			(start -0.12065 0.2794)
			(end -0.12065 0.3048)
			(stroke
				(width 0.1)
				(type default)
			)
			(layer "F.Fab")
		)
		(fp_line
			(start -0.12065 -0.2794)
			(end 0.12065 -0.2794)
			(stroke
				(width 0.1)
				(type default)
			)
			(layer "F.Fab")
		)
		(fp_line
			(start -0.12065 -0.305054)
			(end -0.12065 -0.2794)
			(stroke
				(width 0.1)
				(type default)
			)
			(layer "F.Fab")
		)
		(fp_line
			(start -0.67945 0.3048)
			(end -0.67945 -0.305054)
			(stroke
				(width 0.1)
				(type default)
			)
			(layer "F.Fab")
		)
		(fp_line
			(start -0.67945 -0.305054)
			(end -0.12065 -0.305054)
			(stroke
				(width 0.1)
				(type default)
			)
			(layer "F.Fab")
		)
		(pad "1" smd circle
			(at -0.40005 0 180)
			(size 0 0)
			(layers "F.Cu" "F.Mask" "F.Paste")
			(net "P5V_AUX")
		)
		(pad "2" smd circle
			(at 0.40005 0 180)
			(size 0 0)
			(layers "F.Cu" "F.Mask" "F.Paste")
			(net "P12V_SSD14_PG_G2")
		)
	)
	(footprint ""
		(layer "F.Cu")
		(at 123.67514 -92.605606)
		(property "Reference" "R1583"
			(at 0 0 0)
			(layer "F.SilkS")
			(hide yes)
			(effects
				(font
					(size 1.27 1.27)
				)
			)
		)
		(property "Value" ""
			(at 0 0 0)
			(layer "F.Fab")
			(effects
				(font
					(size 1.27 1.27)
				)
			)
		)
		(duplicate_pad_numbers_are_jumpers no)
		(fp_line
			(start -0.7874 -0.4064)
			(end 0.7874 -0.4064)
			(stroke
				(width 0.1524)
				(type default)
			)
			(layer "F.SilkS")
		)
		(fp_line
			(start -0.7874 0.4064)
			(end -0.7874 -0.4064)
			(stroke
				(width 0.1524)
				(type default)
			)
			(layer "F.SilkS")
		)
		(fp_line
			(start 0.7874 -0.4064)
			(end 0.7874 0.4064)
			(stroke
				(width 0.1524)
				(type default)
			)
			(layer "F.SilkS")
		)
		(fp_line
			(start 0.7874 0.4064)
			(end -0.7874 0.4064)
			(stroke
				(width 0.1524)
				(type default)
			)
			(layer "F.SilkS")
		)
		(fp_line
			(start -0.67945 -0.305054)
			(end -0.12065 -0.305054)
			(stroke
				(width 0.1)
				(type default)
			)
			(layer "F.Fab")
		)
		(fp_line
			(start -0.67945 0.3048)
			(end -0.67945 -0.305054)
			(stroke
				(width 0.1)
				(type default)
			)
			(layer "F.Fab")
		)
		(fp_line
			(start -0.12065 -0.305054)
			(end -0.12065 -0.2794)
			(stroke
				(width 0.1)
				(type default)
			)
			(layer "F.Fab")
		)
		(fp_line
			(start -0.12065 -0.2794)
			(end 0.12065 -0.2794)
			(stroke
				(width 0.1)
				(type default)
			)
			(layer "F.Fab")
		)
		(fp_line
			(start -0.12065 0.2794)
			(end -0.12065 0.3048)
			(stroke
				(width 0.1)
				(type default)
			)
			(layer "F.Fab")
		)
		(fp_line
			(start -0.12065 0.3048)
			(end -0.67945 0.3048)
			(stroke
				(width 0.1)
				(type default)
			)
			(layer "F.Fab")
		)
		(fp_line
			(start 0.120396 0.2794)
			(end -0.12065 0.2794)
			(stroke
				(width 0.1)
				(type default)
			)
			(layer "F.Fab")
		)
		(fp_line
			(start 0.120396 0.3048)
			(end 0.120396 0.2794)
			(stroke
				(width 0.1)
				(type default)
			)
			(layer "F.Fab")
		)
		(fp_line
			(start 0.12065 -0.3048)
			(end 0.67945 -0.3048)
			(stroke
				(width 0.1)
				(type default)
			)
			(layer "F.Fab")
		)
		(fp_line
			(start 0.12065 -0.2794)
			(end 0.12065 -0.3048)
			(stroke
				(width 0.1)
				(type default)
			)
			(layer "F.Fab")
		)
		(fp_line
			(start 0.67945 -0.3048)
			(end 0.67945 0.3048)
			(stroke
				(width 0.1)
				(type default)
			)
			(layer "F.Fab")
		)
		(fp_line
			(start 0.67945 0.3048)
			(end 0.120396 0.3048)
			(stroke
				(width 0.1)
				(type default)
			)
			(layer "F.Fab")
		)
		(pad "1" smd circle
			(at -0.40005 0)
			(size 0 0)
			(layers "F.Cu" "F.Mask" "F.Paste")
			(net "SMB_BIC_I2C9_MUX0_SSD2_R_SDA")
		)
		(pad "2" smd circle
			(at 0.40005 0)
			(size 0 0)
			(layers "F.Cu" "F.Mask" "F.Paste")
			(net "SMB_BIC_I2C9_MUX0_SSD2_SDA")
		)
	)
	(footprint ""
		(layer "F.Cu")
		(at 153.347928 -101.095302)
		(property "Reference" "C272"
			(at 0 0 0)
			(layer "F.SilkS")
			(hide yes)
			(effects
				(font
					(size 1.27 1.27)
				)
			)
		)
		(property "Value" ""
			(at 0 0 0)
			(layer "F.Fab")
			(effects
				(font
					(size 1.27 1.27)
				)
			)
		)
		(duplicate_pad_numbers_are_jumpers no)
		(fp_line
			(start -0.299974 -0.150114)
			(end 0.299974 -0.150114)
			(stroke
				(width 0.1)
				(type default)
			)
			(layer "F.Fab")
		)
		(fp_line
			(start -0.299974 0.150114)
			(end -0.299974 -0.150114)
			(stroke
				(width 0.1)
				(type default)
			)
			(layer "F.Fab")
		)
		(fp_line
			(start 0.299974 -0.150114)
			(end 0.299974 0.150114)
			(stroke
				(width 0.1)
				(type default)
			)
			(layer "F.Fab")
		)
		(fp_line
			(start 0.299974 0.150114)
			(end -0.299974 0.150114)
			(stroke
				(width 0.1)
				(type default)
			)
			(layer "F.Fab")
		)
		(pad "1" smd rect
			(at -0.2667 0)
			(size 0.3048 0.381)
			(layers "F.Cu" "F.Mask" "F.Paste")
			(net "P5E_PEX1_STN1_TX_DN<17>")
		)
		(pad "2" smd rect
			(at 0.2667 0)
			(size 0.3048 0.381)
			(layers "F.Cu" "F.Mask" "F.Paste")
			(net "P5E_PEX1_STN1_TX_C_DN<17>")
		)
	)
)
